# T6G (Grand Teton) — schematic netlist excerpt (pin names and nets, part order shuffled) for the footprints in the layout excerpt that follows; sources: Cadence DE-HDL packaged netlist, KiCad conversion of 04192023_DAF0TMB3IC0_F0TG_MB_C_brd_V02_OCP.brd

R4094  Q_RES  1K 1% CHIP  pkg 0402LF  page 236 : A = P3V3_AUX ; B = OCP_SFF_P3V3_ADC_ALERT_R
R1441  Q_RES  16.9K 1% CHIP  pkg 0402LF  page 259 : A = PWRGD_P12V_MEM_CPU1_EN ; B = GND

(kicad_pcb
	(version 20260206)
	(generator "pcbnew")
	(generator_version "10.0")
	(general
		(thickness 1.6)
		(legacy_teardrops no)
	)
	(paper "A4")
	(title_block
		(title "04192023_DAF0TMB3IC0_F0TG_MB_C_brd_V02_OCP.brd")
		(comment 1 "Grand Teton / footprints 4157-4158 of 8354")
	)
	(layers
		(0 "F.Cu" signal "TOP")
		(4 "In1.Cu" signal "GND")
		(6 "In2.Cu" signal "IN1")
		(8 "In3.Cu" signal "GND1")
		(10 "In4.Cu" signal "IN2")
		(12 "In5.Cu" signal "GND2")
		(14 "In6.Cu" signal "IN3")
		(16 "In7.Cu" signal "GND3")
		(18 "In8.Cu" signal "VCC")
		(20 "In9.Cu" signal "VCC1")
		(22 "In10.Cu" signal "GND4")
		(24 "In11.Cu" signal "IN4")
		(26 "In12.Cu" signal "GND5")
		(28 "In13.Cu" signal "IN5")
		(30 "In14.Cu" signal "GND6")
		(32 "In15.Cu" signal "IN6")
		(34 "In16.Cu" signal "GND7")
		(2 "B.Cu" signal "BOTTOM")
		(9 "F.Adhes" user "F.Adhesive")
		(11 "B.Adhes" user "B.Adhesive")
		(13 "F.Paste" user "Package Geometry/Pastemask Top")
		(15 "B.Paste" user "Package Geometry/Pastemask Bottom")
		(5 "F.SilkS" user "Ref Des/Silkscreen Top")
		(7 "B.SilkS" user "Ref Des/Silkscreen Bottom")
		(1 "F.Mask" user "Board Geometry/Soldermask Top")
		(3 "B.Mask" user "Board Geometry/Soldermask Bottom")
		(17 "Dwgs.User" user "User.Drawings")
		(19 "Cmts.User" user "User.Comments")
		(21 "Eco1.User" user "User.Eco1")
		(23 "Eco2.User" user "User.Eco2")
		(25 "Edge.Cuts" user "Board Geometry/Outline")
		(27 "Margin" user)
		(31 "F.CrtYd" user "Package Geometry/Place Bound Top")
		(29 "B.CrtYd" user "Package Geometry/Place Bound Bottom")
		(35 "F.Fab" user "Ref Des/Assembly Top")
		(33 "B.Fab" user "Ref Des/Assembly Bottom")
	)
	(footprint ""
		(layer "F.Cu")
		(at 448.61988 -94.602808 180)
		(property "Reference" "R4094"
			(at 0 0 180)
			(layer "F.SilkS")
			(hide yes)
			(effects
				(font
					(size 1.27 1.27)
				)
			)
		)
		(property "Value" ""
			(at 0 0 180)
			(layer "F.Fab")
			(effects
				(font
					(size 1.27 1.27)
				)
			)
		)
		(duplicate_pad_numbers_are_jumpers no)
		(fp_line
			(start 0.7874 0.4064)
			(end -0.7874 0.4064)
			(stroke
				(width 0.1524)
				(type default)
			)
			(layer "F.SilkS")
		)
		(fp_line
			(start 0.7874 -0.4064)
			(end 0.7874 0.4064)
			(stroke
				(width 0.1524)
				(type default)
			)
			(layer "F.SilkS")
		)
		(fp_line
			(start -0.7874 0.4064)
			(end -0.7874 -0.4064)
			(stroke
				(width 0.1524)
				(type default)
			)
			(layer "F.SilkS")
		)
		(fp_line
			(start -0.7874 -0.4064)
			(end 0.7874 -0.4064)
			(stroke
				(width 0.1524)
				(type default)
			)
			(layer "F.SilkS")
		)
		(fp_line
			(start 0.67945 0.3048)
			(end 0.120396 0.3048)
			(stroke
				(width 0.1)
				(type default)
			)
			(layer "F.Fab")
		)
		(fp_line
			(start 0.67945 -0.3048)
			(end 0.67945 0.3048)
			(stroke
				(width 0.1)
				(type default)
			)
			(layer "F.Fab")
		)
		(fp_line
			(start 0.12065 -0.2794)
			(end 0.12065 -0.3048)
			(stroke
				(width 0.1)
				(type default)
			)
			(layer "F.Fab")
		)
		(fp_line
			(start 0.12065 -0.3048)
			(end 0.67945 -0.3048)
			(stroke
				(width 0.1)
				(type default)
			)
			(layer "F.Fab")
		)
		(fp_line
			(start 0.120396 0.3048)
			(end 0.120396 0.2794)
			(stroke
				(width 0.1)
				(type default)
			)
			(layer "F.Fab")
		)
		(fp_line
			(start 0.120396 0.2794)
			(end -0.12065 0.2794)
			(stroke
				(width 0.1)
				(type default)
			)
			(layer "F.Fab")
		)
		(fp_line
			(start -0.12065 0.3048)
			(end -0.67945 0.3048)
			(stroke
				(width 0.1)
				(type default)
			)
			(layer "F.Fab")
		)
		(fp_line
			(start -0.12065 0.2794)
			(end -0.12065 0.3048)
			(stroke
				(width 0.1)
				(type default)
			)
			(layer "F.Fab")
		)
		(fp_line
			(start -0.12065 -0.2794)
			(end 0.12065 -0.2794)
			(stroke
				(width 0.1)
				(type default)
			)
			(layer "F.Fab")
		)
		(fp_line
			(start -0.12065 -0.305054)
			(end -0.12065 -0.2794)
			(stroke
				(width 0.1)
				(type default)
			)
			(layer "F.Fab")
		)
		(fp_line
			(start -0.67945 0.3048)
			(end -0.67945 -0.305054)
			(stroke
				(width 0.1)
				(type default)
			)
			(layer "F.Fab")
		)
		(fp_line
			(start -0.67945 -0.305054)
			(end -0.12065 -0.305054)
			(stroke
				(width 0.1)
				(type default)
			)
			(layer "F.Fab")
		)
		(pad "1" smd circle
			(at -0.40005 0 180)
			(size 0 0)
			(layers "F.Cu" "F.Mask" "F.Paste")
			(net "P3V3_AUX")
		)
		(pad "2" smd circle
			(at 0.40005 0 180)
			(size 0 0)
			(layers "F.Cu" "F.Mask" "F.Paste")
			(net "OCP_SFF_P3V3_ADC_ALERT_R")
		)
	)
	(footprint ""
		(layer "F.Cu")
		(at 105.659936 -127.768096 90)
		(property "Reference" "R1441"
			(at 0 0 90)
			(layer "F.SilkS")
			(hide yes)
			(effects
				(font
					(size 1.27 1.27)
				)
			)
		)
		(property "Value" ""
			(at 0 0 90)
			(layer "F.Fab")
			(effects
				(font
					(size 1.27 1.27)
				)
			)
		)
		(duplicate_pad_numbers_are_jumpers no)
		(fp_line
			(start 0.7874 -0.4064)
			(end 0.7874 0.4064)
			(stroke
				(width 0.1524)
				(type default)
			)
			(layer "F.SilkS")
		)
		(fp_line
			(start -0.7874 -0.4064)
			(end 0.7874 -0.4064)
			(stroke
				(width 0.1524)
				(type default)
			)
			(layer "F.SilkS")
		)
		(fp_line
			(start 0.7874 0.4064)
			(end -0.7874 0.4064)
			(stroke
				(width 0.1524)
				(type default)
			)
			(layer "F.SilkS")
		)
		(fp_line
			(start -0.7874 0.4064)
			(end -0.7874 -0.4064)
			(stroke
				(width 0.1524)
				(type default)
			)
			(layer "F.SilkS")
		)
		(fp_line
			(start -0.12065 -0.305054)
			(end -0.12065 -0.2794)
			(stroke
				(width 0.1)
				(type default)
			)
			(layer "F.Fab")
		)
		(fp_line
			(start -0.67945 -0.305054)
			(end -0.12065 -0.305054)
			(stroke
				(width 0.1)
				(type default)
			)
			(layer "F.Fab")
		)
		(fp_line
			(start 0.67945 -0.3048)
			(end 0.67945 0.3048)
			(stroke
				(width 0.1)
				(type default)
			)
			(layer "F.Fab")
		)
		(fp_line
			(start 0.12065 -0.3048)
			(end 0.67945 -0.3048)
			(stroke
				(width 0.1)
				(type default)
			)
			(layer "F.Fab")
		)
		(fp_line
			(start 0.12065 -0.2794)
			(end 0.12065 -0.3048)
			(stroke
				(width 0.1)
				(type default)
			)
			(layer "F.Fab")
		)
		(fp_line
			(start -0.12065 -0.2794)
			(end 0.12065 -0.2794)
			(stroke
				(width 0.1)
				(type default)
			)
			(layer "F.Fab")
		)
		(fp_line
			(start 0.120396 0.2794)
			(end -0.12065 0.2794)
			(stroke
				(width 0.1)
				(type default)
			)
			(layer "F.Fab")
		)
		(fp_line
			(start -0.12065 0.2794)
			(end -0.12065 0.3048)
			(stroke
				(width 0.1)
				(type default)
			)
			(layer "F.Fab")
		)
		(fp_line
			(start 0.67945 0.3048)
			(end 0.120396 0.3048)
			(stroke
				(width 0.1)
				(type default)
			)
			(layer "F.Fab")
		)
		(fp_line
			(start 0.120396 0.3048)
			(end 0.120396 0.2794)
			(stroke
				(width 0.1)
				(type default)
			)
			(layer "F.Fab")
		)
		(fp_line
			(start -0.12065 0.3048)
			(end -0.67945 0.3048)
			(stroke
				(width 0.1)
				(type default)
			)
			(layer "F.Fab")
		)
		(fp_line
			(start -0.67945 0.3048)
			(end -0.67945 -0.305054)
			(stroke
				(width 0.1)
				(type default)
			)
			(layer "F.Fab")
		)
		(pad "1" smd circle
			(at -0.40005 0 90)
			(size 0 0)
			(layers "F.Cu" "F.Mask" "F.Paste")
			(net "PWRGD_P12V_MEM_CPU1_EN")
		)
		(pad "2" smd circle
			(at 0.40005 0 90)
			(size 0 0)
			(layers "F.Cu" "F.Mask" "F.Paste")
			(net "GND")
		)
	)
)
